# T6G (Grand Teton) — schematic netlist excerpt (pin names and nets, part order shuffled) for the footprints in the layout excerpt that follows; sources: Cadence DE-HDL packaged netlist, KiCad conversion of 04192023_DAF0TMB3IC0_F0TG_MB_C_brd_V02_OCP.brd

X6  TP_TDR_4P_FTS  TP_TDR_4P_DIP EMPTY  pkg TH  page 260
  S1  = TDR_DIFF_80_BOT_DP
  P1  = T1_GND
  P2  = T1_GND
  S2  = TDR_DIFF_80_BOT_DN

C517  Q_CAP  0.1UF 10V 10% X7S  pkg C0201  page 279 : A = P1V8_CPU0_RT0_1A ; B = GND

(kicad_pcb
	(version 20260206)
	(generator "pcbnew")
	(generator_version "10.0")
	(general
		(thickness 1.6)
		(legacy_teardrops no)
	)
	(paper "A4")
	(title_block
		(title "04192023_DAF0TMB3IC0_F0TG_MB_C_brd_V02_OCP.brd")
		(comment 1 "Grand Teton / footprints 5271-5272 of 8354")
	)
	(layers
		(0 "F.Cu" signal "TOP")
		(4 "In1.Cu" signal "GND")
		(6 "In2.Cu" signal "IN1")
		(8 "In3.Cu" signal "GND1")
		(10 "In4.Cu" signal "IN2")
		(12 "In5.Cu" signal "GND2")
		(14 "In6.Cu" signal "IN3")
		(16 "In7.Cu" signal "GND3")
		(18 "In8.Cu" signal "VCC")
		(20 "In9.Cu" signal "VCC1")
		(22 "In10.Cu" signal "GND4")
		(24 "In11.Cu" signal "IN4")
		(26 "In12.Cu" signal "GND5")
		(28 "In13.Cu" signal "IN5")
		(30 "In14.Cu" signal "GND6")
		(32 "In15.Cu" signal "IN6")
		(34 "In16.Cu" signal "GND7")
		(2 "B.Cu" signal "BOTTOM")
		(9 "F.Adhes" user "F.Adhesive")
		(11 "B.Adhes" user "B.Adhesive")
		(13 "F.Paste" user "Package Geometry/Pastemask Top")
		(15 "B.Paste" user "Package Geometry/Pastemask Bottom")
		(5 "F.SilkS" user "Ref Des/Silkscreen Top")
		(7 "B.SilkS" user "Ref Des/Silkscreen Bottom")
		(1 "F.Mask" user "Board Geometry/Soldermask Top")
		(3 "B.Mask" user "Board Geometry/Soldermask Bottom")
		(17 "Dwgs.User" user "User.Drawings")
		(19 "Cmts.User" user "User.Comments")
		(21 "Eco1.User" user "User.Eco1")
		(23 "Eco2.User" user "User.Eco2")
		(25 "Edge.Cuts" user "Board Geometry/Outline")
		(27 "Margin" user)
		(31 "F.CrtYd" user "Package Geometry/Place Bound Top")
		(29 "B.CrtYd" user "Package Geometry/Place Bound Bottom")
		(35 "F.Fab" user "Ref Des/Assembly Top")
		(33 "B.Fab" user "Ref Des/Assembly Bottom")
	)
	(footprint ""
		(layer "B.Cu")
		(at 488.03433 -147.888198 90)
		(property "Reference" "X6"
			(at 1.112012 2.605024 270)
			(unlocked yes)
			(layer "B.SilkS")
			(effects
				(font
					(size 0.7874 0.5842)
					(thickness 0.1524)
				)
				(justify left mirror)
			)
		)
		(property "Value" ""
			(at 0 0 90)
			(layer "B.Fab")
			(effects
				(font
					(size 1.27 1.27)
				)
				(justify mirror)
			)
		)
		(property "Device Type" "TP_TDR_4P_FTS_TH-TP_TDR_4P_DIP,EMPTY,TP15"
			(at -1.30175 1.27 0)
			(unlocked yes)
			(layer "B.Fab")
			(hide yes)
			(effects
				(font
					(size 0.635 0.4064)
					(thickness 0.1524)
				)
				(justify mirror)
			)
		)
		(property "User Part Number" "N_A"
			(at -1.30175 1.27 0)
			(unlocked yes)
			(layer "Cmts.User")
			(hide yes)
			(effects
				(font
					(size 0.635 0.4064)
					(thickness 0.1524)
				)
				(justify mirror)
			)
		)
		(duplicate_pad_numbers_are_jumpers no)
		(fp_line
			(start 0 -1.27)
			(end 0 -0.635)
			(stroke
				(width 0.1524)
				(type default)
			)
			(layer "B.SilkS")
		)
		(fp_line
			(start -2.54 -1.27)
			(end 0 -1.27)
			(stroke
				(width 0.1524)
				(type default)
			)
			(layer "B.SilkS")
		)
		(fp_line
			(start -2.54 -1.1303)
			(end -2.54 -1.27)
			(stroke
				(width 0.1524)
				(type default)
			)
			(layer "B.SilkS")
		)
		(fp_line
			(start 0 0.635)
			(end 0 1.905)
			(stroke
				(width 0.1524)
				(type default)
			)
			(layer "B.SilkS")
		)
		(fp_line
			(start -2.54 1.4097)
			(end -2.54 1.1303)
			(stroke
				(width 0.1524)
				(type default)
			)
			(layer "B.SilkS")
		)
		(fp_line
			(start 0 3.175)
			(end 0 3.81)
			(stroke
				(width 0.1524)
				(type default)
			)
			(layer "B.SilkS")
		)
		(fp_line
			(start 0 3.81)
			(end -2.54 3.81)
			(stroke
				(width 0.1524)
				(type default)
			)
			(layer "B.SilkS")
		)
		(fp_line
			(start -2.54 3.81)
			(end -2.54 3.6703)
			(stroke
				(width 0.1524)
				(type default)
			)
			(layer "B.SilkS")
		)
		(fp_poly
			(pts
				(xy 2.285746 -0.762) (xy 2.285746 0.762) (xy 0.761746 0)
			)
			(stroke
				(width 0)
				(type default)
			)
			(fill yes)
			(layer "B.SilkS")
		)
		(fp_line
			(start 0 -1.27)
			(end 0 3.81)
			(stroke
				(width 0.1)
				(type default)
			)
			(layer "B.Fab")
		)
		(fp_line
			(start -2.54 -1.27)
			(end 0 -1.27)
			(stroke
				(width 0.1)
				(type default)
			)
			(layer "B.Fab")
		)
		(fp_line
			(start 0 3.81)
			(end -2.54 3.81)
			(stroke
				(width 0.1)
				(type default)
			)
			(layer "B.Fab")
		)
		(fp_line
			(start -2.54 3.81)
			(end -2.54 -1.27)
			(stroke
				(width 0.1)
				(type default)
			)
			(layer "B.Fab")
		)
		(fp_poly
			(pts
				(xy 0.761746 0) (xy 2.285746 -0.762) (xy 2.285746 0.762)
			)
			(stroke
				(width 0)
				(type default)
			)
			(fill yes)
			(layer "B.Fab")
		)
		(pad "1" thru_hole circle
			(at 0 0 270)
			(size 1.0033 1.0033)
			(drill 0.249936)
			(layers "*.Cu" "*.Mask")
			(remove_unused_layers no)
			(net "TDR_DIFF_80_BOT_DP")
			(clearance 0.10795)
			(padstack
				(mode front_inner_back)
				(layer "Inner"
					(shape circle)
					(size 0.8001 0.8001)
					(clearance 0.1524)
				)
				(layer "B.Cu"
					(shape circle)
					(size 1.0033 1.0033)
					(thermal_gap 0.10795)
					(clearance 0.10795)
				)
			)
		)
		(pad "2" thru_hole circle
			(at -2.54 0 270)
			(size 1.9939 1.9939)
			(drill 0.249936)
			(layers "*.Cu" "*.Mask")
			(remove_unused_layers no)
			(net "T1_GND")
			(clearance 0.10795)
			(padstack
				(mode front_inner_back)
				(layer "Inner"
					(shape circle)
					(size 0.8001 0.8001)
					(clearance 0.1524)
				)
				(layer "B.Cu"
					(shape circle)
					(size 1.9939 1.9939)
					(thermal_gap 0.10795)
					(clearance 0.10795)
				)
			)
		)
		(pad "3" thru_hole circle
			(at -2.54 2.54 270)
			(size 1.9939 1.9939)
			(drill 0.249936)
			(layers "*.Cu" "*.Mask")
			(remove_unused_layers no)
			(net "T1_GND")
			(clearance 0.10795)
			(padstack
				(mode front_inner_back)
				(layer "Inner"
					(shape circle)
					(size 0.8001 0.8001)
					(clearance 0.1524)
				)
				(layer "B.Cu"
					(shape circle)
					(size 1.9939 1.9939)
					(thermal_gap 0.10795)
					(clearance 0.10795)
				)
			)
		)
		(pad "4" thru_hole circle
			(at 0 2.54 270)
			(size 1.0033 1.0033)
			(drill 0.249936)
			(layers "*.Cu" "*.Mask")
			(remove_unused_layers no)
			(net "TDR_DIFF_80_BOT_DN")
			(clearance 0.10795)
			(padstack
				(mode front_inner_back)
				(layer "Inner"
					(shape circle)
					(size 0.8001 0.8001)
					(clearance 0.1524)
				)
				(layer "B.Cu"
					(shape circle)
					(size 1.0033 1.0033)
					(thermal_gap 0.10795)
					(clearance 0.10795)
				)
			)
		)
	)
	(footprint ""
		(layer "B.Cu")
		(at 311.778396 -395.148562 90)
		(property "Reference" "C517"
			(at 0 0 90)
			(layer "B.SilkS")
			(hide yes)
			(effects
				(font
					(size 1.27 1.27)
				)
				(justify mirror)
			)
		)
		(property "Value" ""
			(at 0 0 90)
			(layer "B.Fab")
			(effects
				(font
					(size 1.27 1.27)
				)
				(justify mirror)
			)
		)
		(duplicate_pad_numbers_are_jumpers no)
		(fp_line
			(start 0.299974 -0.150114)
			(end -0.299974 -0.150114)
			(stroke
				(width 0.1)
				(type default)
			)
			(layer "B.Fab")
		)
		(fp_line
			(start -0.299974 -0.150114)
			(end -0.299974 0.150114)
			(stroke
				(width 0.1)
				(type default)
			)
			(layer "B.Fab")
		)
		(fp_line
			(start 0.299974 0.150114)
			(end 0.299974 -0.150114)
			(stroke
				(width 0.1)
				(type default)
			)
			(layer "B.Fab")
		)
		(fp_line
			(start -0.299974 0.150114)
			(end 0.299974 0.150114)
			(stroke
				(width 0.1)
				(type default)
			)
			(layer "B.Fab")
		)
		(pad "1" smd rect
			(at 0.2667 0 270)
			(size 0.3048 0.381)
			(layers "B.Cu" "B.Mask" "B.Paste")
			(net "P1V8_CPU0_RT0_1A")
		)
		(pad "2" smd rect
			(at -0.2667 0 270)
			(size 0.3048 0.381)
			(layers "B.Cu" "B.Mask" "B.Paste")
			(net "GND")
		)
	)
)
